# T6G (Grand Teton) — schematic netlist excerpt (pin names and nets, part order shuffled) for the footprints in the layout excerpt that follows; sources: Cadence DE-HDL packaged netlist, KiCad conversion of 04192023_DAF0TMB3IC0_F0TG_MB_C_brd_V02_OCP.brd

PC100  Q_CAPP  220UF 4V 20% SPCAP  pkg SMLF  page 201 : A = PVDDCR_CPU1_P0 ; B = GND
R648  Q_RES  33 5% CHIP  pkg 0402LF  page 81 : A = E1S_0_P3V3_EN ; B = P3V3_E1S_0_EN_R

(kicad_pcb
	(version 20260206)
	(generator "pcbnew")
	(generator_version "10.0")
	(general
		(thickness 1.6)
		(legacy_teardrops no)
	)
	(paper "A4")
	(title_block
		(title "04192023_DAF0TMB3IC0_F0TG_MB_C_brd_V02_OCP.brd")
		(comment 1 "Grand Teton / footprints 6280-6281 of 8354")
	)
	(layers
		(0 "F.Cu" signal "TOP")
		(4 "In1.Cu" signal "GND")
		(6 "In2.Cu" signal "IN1")
		(8 "In3.Cu" signal "GND1")
		(10 "In4.Cu" signal "IN2")
		(12 "In5.Cu" signal "GND2")
		(14 "In6.Cu" signal "IN3")
		(16 "In7.Cu" signal "GND3")
		(18 "In8.Cu" signal "VCC")
		(20 "In9.Cu" signal "VCC1")
		(22 "In10.Cu" signal "GND4")
		(24 "In11.Cu" signal "IN4")
		(26 "In12.Cu" signal "GND5")
		(28 "In13.Cu" signal "IN5")
		(30 "In14.Cu" signal "GND6")
		(32 "In15.Cu" signal "IN6")
		(34 "In16.Cu" signal "GND7")
		(2 "B.Cu" signal "BOTTOM")
		(9 "F.Adhes" user "F.Adhesive")
		(11 "B.Adhes" user "B.Adhesive")
		(13 "F.Paste" user "Package Geometry/Pastemask Top")
		(15 "B.Paste" user "Package Geometry/Pastemask Bottom")
		(5 "F.SilkS" user "Ref Des/Silkscreen Top")
		(7 "B.SilkS" user "Ref Des/Silkscreen Bottom")
		(1 "F.Mask" user "Board Geometry/Soldermask Top")
		(3 "B.Mask" user "Board Geometry/Soldermask Bottom")
		(17 "Dwgs.User" user "User.Drawings")
		(19 "Cmts.User" user "User.Comments")
		(21 "Eco1.User" user "User.Eco1")
		(23 "Eco2.User" user "User.Eco2")
		(25 "Edge.Cuts" user "Board Geometry/Outline")
		(27 "Margin" user)
		(31 "F.CrtYd" user "Package Geometry/Place Bound Top")
		(29 "B.CrtYd" user "Package Geometry/Place Bound Bottom")
		(35 "F.Fab" user "Ref Des/Assembly Top")
		(33 "B.Fab" user "Ref Des/Assembly Bottom")
	)
	(footprint ""
		(layer "B.Cu")
		(at 200.952608 -120.737376)
		(property "Reference" "R648"
			(at 0 0 0)
			(layer "B.SilkS")
			(hide yes)
			(effects
				(font
					(size 1.27 1.27)
				)
				(justify mirror)
			)
		)
		(property "Value" ""
			(at 0 0 0)
			(layer "B.Fab")
			(effects
				(font
					(size 1.27 1.27)
				)
				(justify mirror)
			)
		)
		(duplicate_pad_numbers_are_jumpers no)
		(fp_line
			(start -0.7874 -0.4064)
			(end -0.7874 0.4064)
			(stroke
				(width 0.1524)
				(type default)
			)
			(layer "B.SilkS")
		)
		(fp_line
			(start -0.7874 0.4064)
			(end 0.7874 0.4064)
			(stroke
				(width 0.1524)
				(type default)
			)
			(layer "B.SilkS")
		)
		(fp_line
			(start 0.7874 -0.4064)
			(end -0.7874 -0.4064)
			(stroke
				(width 0.1524)
				(type default)
			)
			(layer "B.SilkS")
		)
		(fp_line
			(start 0.7874 0.4064)
			(end 0.7874 -0.4064)
			(stroke
				(width 0.1524)
				(type default)
			)
			(layer "B.SilkS")
		)
		(fp_line
			(start -0.67945 -0.3048)
			(end -0.67945 0.3048)
			(stroke
				(width 0.1)
				(type default)
			)
			(layer "B.Fab")
		)
		(fp_line
			(start -0.67945 0.3048)
			(end -0.120396 0.3048)
			(stroke
				(width 0.1)
				(type default)
			)
			(layer "B.Fab")
		)
		(fp_line
			(start -0.12065 -0.3048)
			(end -0.67945 -0.3048)
			(stroke
				(width 0.1)
				(type default)
			)
			(layer "B.Fab")
		)
		(fp_line
			(start -0.12065 -0.2794)
			(end -0.12065 -0.3048)
			(stroke
				(width 0.1)
				(type default)
			)
			(layer "B.Fab")
		)
		(fp_line
			(start -0.120396 0.2794)
			(end 0.12065 0.2794)
			(stroke
				(width 0.1)
				(type default)
			)
			(layer "B.Fab")
		)
		(fp_line
			(start -0.120396 0.3048)
			(end -0.120396 0.2794)
			(stroke
				(width 0.1)
				(type default)
			)
			(layer "B.Fab")
		)
		(fp_line
			(start 0.12065 -0.305054)
			(end 0.12065 -0.2794)
			(stroke
				(width 0.1)
				(type default)
			)
			(layer "B.Fab")
		)
		(fp_line
			(start 0.12065 -0.2794)
			(end -0.12065 -0.2794)
			(stroke
				(width 0.1)
				(type default)
			)
			(layer "B.Fab")
		)
		(fp_line
			(start 0.12065 0.2794)
			(end 0.12065 0.3048)
			(stroke
				(width 0.1)
				(type default)
			)
			(layer "B.Fab")
		)
		(fp_line
			(start 0.12065 0.3048)
			(end 0.67945 0.3048)
			(stroke
				(width 0.1)
				(type default)
			)
			(layer "B.Fab")
		)
		(fp_line
			(start 0.67945 -0.305054)
			(end 0.12065 -0.305054)
			(stroke
				(width 0.1)
				(type default)
			)
			(layer "B.Fab")
		)
		(fp_line
			(start 0.67945 0.3048)
			(end 0.67945 -0.305054)
			(stroke
				(width 0.1)
				(type default)
			)
			(layer "B.Fab")
		)
		(pad "1" smd circle
			(at 0.40005 0 180)
			(size 0 0)
			(layers "B.Cu" "B.Mask" "B.Paste")
			(net "E1S_0_P3V3_EN")
		)
		(pad "2" smd circle
			(at -0.40005 0 180)
			(size 0 0)
			(layers "B.Cu" "B.Mask" "B.Paste")
			(net "P3V3_E1S_0_EN_R")
		)
	)
	(footprint ""
		(layer "B.Cu")
		(at 352.24466 -333.121 -90)
		(property "Reference" "PC100"
			(at 9.640316 0.988314 270)
			(unlocked yes)
			(layer "B.SilkS")
			(effects
				(font
					(size 0.7874 0.5842)
					(thickness 0.1524)
				)
				(justify left mirror)
			)
		)
		(property "Value" ""
			(at 0 0 90)
			(layer "B.Fab")
			(effects
				(font
					(size 1.27 1.27)
				)
				(justify mirror)
			)
		)
		(duplicate_pad_numbers_are_jumpers no)
		(fp_line
			(start -4.533392 2.249932)
			(end 4.533392 2.249932)
			(stroke
				(width 0.1524)
				(type default)
			)
			(layer "B.SilkS")
		)
		(fp_line
			(start 4.533392 2.249932)
			(end 4.533392 -2.249932)
			(stroke
				(width 0.1524)
				(type default)
			)
			(layer "B.SilkS")
		)
		(fp_line
			(start -4.533392 -2.249932)
			(end -4.533392 2.249932)
			(stroke
				(width 0.1524)
				(type default)
			)
			(layer "B.SilkS")
		)
		(fp_line
			(start 4.533392 -2.249932)
			(end -4.533392 -2.249932)
			(stroke
				(width 0.1524)
				(type default)
			)
			(layer "B.SilkS")
		)
		(fp_rect
			(start 5.39242 2.326132)
			(end 4.533392 -2.326132)
			(stroke
				(width 0)
				(type default)
			)
			(fill yes)
			(layer "B.SilkS")
		)
		(fp_line
			(start -3.750056 2.249932)
			(end 3.750056 2.249932)
			(stroke
				(width 0.1)
				(type default)
			)
			(layer "B.Fab")
		)
		(fp_line
			(start 3.750056 2.249932)
			(end 3.750056 -2.249932)
			(stroke
				(width 0.1)
				(type default)
			)
			(layer "B.Fab")
		)
		(fp_line
			(start -3.750056 -2.249932)
			(end -3.750056 2.249932)
			(stroke
				(width 0.1)
				(type default)
			)
			(layer "B.Fab")
		)
		(fp_line
			(start 3.750056 -2.249932)
			(end -3.750056 -2.249932)
			(stroke
				(width 0.1)
				(type default)
			)
			(layer "B.Fab")
		)
		(fp_text user "-"
			(at -4.36499 2.896108 270)
			(unlocked yes)
			(layer "B.SilkS")
			(effects
				(font
					(size 1.905 1.4224)
					(thickness 0.1524)
				)
				(justify left mirror)
			)
		)
		(fp_text user "+"
			(at 6.322314 0.786384 180)
			(unlocked yes)
			(layer "B.SilkS")
			(effects
				(font
					(size 1.905 1.4224)
					(thickness 0.1524)
				)
				(justify left mirror)
			)
		)
		(fp_text user "+"
			(at 6.322314 0.786384 180)
			(unlocked yes)
			(layer "B.Fab")
			(effects
				(font
					(size 1.905 1.4224)
					(thickness 0.1524)
				)
				(justify left mirror)
			)
		)
		(fp_text user "-"
			(at -4.8514 -0.14605 270)
			(unlocked yes)
			(layer "B.Fab")
			(effects
				(font
					(size 1.905 1.4224)
					(thickness 0.1524)
				)
				(justify left mirror)
			)
		)
		(pad "1" smd rect
			(at 3.199892 0 90)
			(size 2.413 2.8194)
			(layers "B.Cu" "B.Mask" "B.Paste")
			(net "PVDDCR_CPU1_P0")
		)
		(pad "2" smd rect
			(at -3.199892 0 90)
			(size 2.413 2.8194)
			(layers "B.Cu" "B.Mask" "B.Paste")
			(net "GND")
		)
	)
)
